(kicad_pcb
	(version 20241229)
	(generator "pcbnew")
	(generator_version "9.0")
	(general
		(thickness 1.61)
		(legacy_teardrops no)
	)
	(paper "A3")
	(title_block
		(title "SO-DIMM DDR5 Tester")
		(date "2025-11-26")
		(rev "1.3.0")
		(comment 9 "footprints 455-460 of 627")
	)
	(layers
		(0 "F.Cu" signal)
		(4 "In1.Cu" power)
		(6 "In2.Cu" mixed)
		(8 "In3.Cu" power)
		(10 "In4.Cu" mixed)
		(12 "In5.Cu" power)
		(14 "In6.Cu" mixed)
		(16 "In7.Cu" power)
		(18 "In8.Cu" power)
		(20 "In9.Cu" mixed)
		(22 "In10.Cu" power)
		(2 "B.Cu" signal)
		(9 "F.Adhes" user "F.Adhesive")
		(11 "B.Adhes" user "B.Adhesive")
		(13 "F.Paste" user)
		(15 "B.Paste" user)
		(5 "F.SilkS" user "F.Silkscreen")
		(7 "B.SilkS" user "B.Silkscreen")
		(1 "F.Mask" user)
		(3 "B.Mask" user)
		(17 "Dwgs.User" user "User.Drawings")
		(19 "Cmts.User" user "User.Comments")
		(21 "Eco1.User" user "User.Eco1")
		(23 "Eco2.User" user "User.Eco2")
		(25 "Edge.Cuts" user)
		(27 "Margin" user)
		(31 "F.CrtYd" user "F.Courtyard")
		(29 "B.CrtYd" user "B.Courtyard")
		(35 "F.Fab" user)
		(33 "B.Fab" user)
	)
	(footprint "antmicro-footprints:C_0402_1005Metric"
		(layer "B.Cu")
		(at 144.877001 184.3005)
		(descr "Capacitor SMD 0402 (1005 Metric), square (rectangular) end terminal, IPC_7351 nominal, (Body size source: IPC-SM-782 page 76, https://www.pcb-3d.com/wordpress/wp-content/uploads/ipc-sm-782a_amendment_1_and_2.pdf)")
		(tags "capacitor 0402")
		(property "Reference" "C57"
			(at 0 1.17 180)
			(layer "B.SilkS")
			(hide yes)
			(effects
				(font
					(size 0.7 0.7)
					(thickness 0.15)
				)
				(justify left bottom mirror)
			)
		)
		(property "Value" "C_4u7_0402"
			(at 0 -1.169 180)
			(layer "B.Fab")
			(effects
				(font
					(size 0.7 0.7)
					(thickness 0.15)
				)
				(justify left bottom mirror)
			)
		)
		(property "Datasheet" "https://www.murata.com/products/productdetail?partno=GRM155R61A475MEAA%23"
			(at 0 0 0)
			(layer "F.Fab")
			(hide yes)
			(effects
				(font
					(size 1.27 1.27)
					(thickness 0.15)
				)
			)
		)
		(property "Author" "Antmicro"
			(at 0 0 0)
			(layer "B.Fab")
			(hide yes)
			(effects
				(font
					(size 1 1)
					(thickness 0.15)
				)
				(justify mirror)
			)
		)
		(property "Dielectric" ""
			(at 0 0 0)
			(layer "B.Fab")
			(hide yes)
			(effects
				(font
					(size 1 1)
					(thickness 0.15)
				)
				(justify mirror)
			)
		)
		(property "License" "Apache-2.0"
			(at 0 0 0)
			(layer "B.Fab")
			(hide yes)
			(effects
				(font
					(size 1 1)
					(thickness 0.15)
				)
				(justify mirror)
			)
		)
		(property "MPN" "GRM155R61A475MEAAD"
			(at 0 0 0)
			(layer "B.Fab")
			(hide yes)
			(effects
				(font
					(size 1 1)
					(thickness 0.15)
				)
				(justify mirror)
			)
		)
		(property "Manufacturer" "Murata"
			(at 0 0 0)
			(layer "B.Fab")
			(hide yes)
			(effects
				(font
					(size 1 1)
					(thickness 0.15)
				)
				(justify mirror)
			)
		)
		(property "Val" "4u7"
			(at 0 0 0)
			(layer "B.Fab")
			(hide yes)
			(effects
				(font
					(size 1 1)
					(thickness 0.15)
				)
				(justify mirror)
			)
		)
		(property "Voltage" ""
			(at 0 0 0)
			(layer "B.Fab")
			(hide yes)
			(effects
				(font
					(size 1 1)
					(thickness 0.15)
				)
				(justify mirror)
			)
		)
		(sheetname "/FPGA power/")
		(sheetfile "fpga-power.kicad_sch")
		(attr smd)
		(fp_rect
			(start -0.9656 0.4572)
			(end 0.9652 -0.4828)
			(stroke
				(width 0.05)
				(type solid)
			)
			(fill no)
			(layer "B.CrtYd")
		)
		(fp_line
			(start -0.5 -0.248)
			(end -0.5 0.25)
			(stroke
				(width 0.15)
				(type solid)
			)
			(layer "B.Fab")
		)
		(fp_line
			(start -0.5 0.25)
			(end 0.498 0.25)
			(stroke
				(width 0.15)
				(type solid)
			)
			(layer "B.Fab")
		)
		(fp_line
			(start 0.498 -0.248)
			(end -0.5 -0.248)
			(stroke
				(width 0.15)
				(type solid)
			)
			(layer "B.Fab")
		)
		(fp_line
			(start 0.498 0.25)
			(end 0.498 -0.248)
			(stroke
				(width 0.15)
				(type solid)
			)
			(layer "B.Fab")
		)
		(pad "1" smd roundrect
			(at -0.5 0 270)
			(size 0.6 0.6)
			(layers "B.Cu" "B.Mask" "B.Paste")
			(roundrect_rratio 0.25)
			(net 188 "+1V8")
			(pintype "passive")
		)
		(pad "2" smd roundrect
			(at 0.498 0)
			(size 0.6 0.6)
			(layers "B.Cu" "B.Mask" "B.Paste")
			(roundrect_rratio 0.25)
			(net 1 "GND")
			(pintype "passive")
		)
	)
	(footprint "antmicro-footprints:R_0402_1005Metric"
		(layer "B.Cu")
		(at 195.415 146.851)
		(descr "Resistor SMD 0402")
		(tags "resistor SMD 0402")
		(property "Reference" "R187"
			(at -1.122484 0.772697 180)
			(layer "B.SilkS")
			(hide yes)
			(effects
				(font
					(size 0.7 0.7)
					(thickness 0.15)
				)
				(justify left bottom mirror)
			)
		)
		(property "Value" "R_47k_0402"
			(at -1.011843 -1.772047 180)
			(layer "B.Fab")
			(effects
				(font
					(size 0.7 0.7)
					(thickness 0.15)
				)
				(justify left bottom mirror)
			)
		)
		(property "Datasheet" "https://www.bourns.com/docs/product-datasheets/cr.pdf"
			(at 0 0 0)
			(layer "F.Fab")
			(hide yes)
			(effects
				(font
					(size 1.27 1.27)
					(thickness 0.15)
				)
			)
		)
		(property "Author" "Antmicro"
			(at 0 0 0)
			(layer "B.Fab")
			(hide yes)
			(effects
				(font
					(size 1 1)
					(thickness 0.15)
				)
				(justify mirror)
			)
		)
		(property "License" "Apache-2.0"
			(at 0 0 0)
			(layer "B.Fab")
			(hide yes)
			(effects
				(font
					(size 1 1)
					(thickness 0.15)
				)
				(justify mirror)
			)
		)
		(property "MPN" "CR0402-FX-4702GLF"
			(at 0 0 0)
			(layer "B.Fab")
			(hide yes)
			(effects
				(font
					(size 1 1)
					(thickness 0.15)
				)
				(justify mirror)
			)
		)
		(property "Manufacturer" "Bourns"
			(at 0 0 0)
			(layer "B.Fab")
			(hide yes)
			(effects
				(font
					(size 1 1)
					(thickness 0.15)
				)
				(justify mirror)
			)
		)
		(property "Tolerance" "1%"
			(at 0 0 0)
			(layer "B.Fab")
			(hide yes)
			(effects
				(font
					(size 1 1)
					(thickness 0.15)
				)
				(justify mirror)
			)
		)
		(property "Val" "47k"
			(at 0 0 0)
			(layer "B.Fab")
			(hide yes)
			(effects
				(font
					(size 1 1)
					(thickness 0.15)
				)
				(justify mirror)
			)
		)
		(sheetname "/Supply/")
		(sheetfile "supply.kicad_sch")
		(attr smd)
		(fp_rect
			(start -0.93 0.47)
			(end 0.93 -0.47)
			(stroke
				(width 0.05)
				(type solid)
			)
			(fill no)
			(layer "B.CrtYd")
		)
		(fp_rect
			(start -0.5 0.25)
			(end 0.5 -0.25)
			(stroke
				(width 0.15)
				(type solid)
			)
			(fill no)
			(layer "B.Fab")
		)
		(pad "1" smd roundrect
			(at -0.485 0)
			(size 0.59 0.64)
			(layers "B.Cu" "B.Mask" "B.Paste")
			(roundrect_rratio 0.25)
			(net 222 "/Supply/EN2")
			(pintype "passive")
		)
		(pad "2" smd roundrect
			(at 0.485 0)
			(size 0.59 0.64)
			(layers "B.Cu" "B.Mask" "B.Paste")
			(roundrect_rratio 0.25)
			(net 41 "+3V3_AON")
			(pintype "passive")
		)
	)
	(footprint "antmicro-footprints:TP_SMD_1mm"
		(layer "B.Cu")
		(at 203.1 151.8 90)
		(property "Reference" "TP41"
			(at 0.5 -0.4 270)
			(layer "B.SilkS")
			(effects
				(font
					(size 0.7 0.7)
					(thickness 0.15)
				)
				(justify right top mirror)
			)
		)
		(property "Value" "TP_1mm_SMD"
			(at 0 -1.4 90)
			(layer "B.Fab")
			(effects
				(font
					(size 0.7 0.7)
					(thickness 0.15)
				)
				(justify right top mirror)
			)
		)
		(property "MPN" ""
			(at 0 0 270)
			(unlocked yes)
			(layer "B.Fab")
			(hide yes)
			(effects
				(font
					(size 1 1)
					(thickness 0.15)
				)
				(justify mirror)
			)
		)
		(property "Manufacturer" ""
			(at 0 0 270)
			(unlocked yes)
			(layer "B.Fab")
			(hide yes)
			(effects
				(font
					(size 1 1)
					(thickness 0.15)
				)
				(justify mirror)
			)
		)
		(property "Author" "Antmicro"
			(at 0 0 270)
			(unlocked yes)
			(layer "B.Fab")
			(hide yes)
			(effects
				(font
					(size 1 1)
					(thickness 0.15)
				)
				(justify mirror)
			)
		)
		(property "License" "Apache-2.0"
			(at 0 0 270)
			(unlocked yes)
			(layer "B.Fab")
			(hide yes)
			(effects
				(font
					(size 1 1)
					(thickness 0.15)
				)
				(justify mirror)
			)
		)
		(sheetname "/I^{2}C/")
		(sheetfile "i2c.kicad_sch")
		(attr exclude_from_pos_files)
		(fp_circle
			(center 0 0)
			(end 0.6 0)
			(stroke
				(width 0.05)
				(type default)
			)
			(fill no)
			(layer "B.CrtYd")
		)
		(fp_text user "${REFERENCE}"
			(at -0.5 -2.8 90)
			(layer "B.Fab")
			(effects
				(font
					(size 0.7 0.7)
					(thickness 0.15)
				)
				(justify right top mirror)
			)
		)
		(fp_text user "Author: Antmicro"
			(at -0.5 -4 90)
			(layer "B.Fab")
			(effects
				(font
					(size 0.7 0.7)
					(thickness 0.15)
				)
				(justify right top mirror)
			)
		)
		(fp_text user "License: Apache-2.0"
			(at -0.5 -5.2 90)
			(layer "B.Fab")
			(effects
				(font
					(size 0.7 0.7)
					(thickness 0.15)
				)
				(justify right top mirror)
			)
		)
		(pad "1" smd circle
			(at 0 0 90)
			(size 1 1)
			(layers "B.Cu" "B.Mask")
			(net 687 "IN2")
			(pinfunction "1")
			(pintype "passive")
		)
	)
	(footprint "antmicro-footprints:C_0402_1005Metric"
		(layer "B.Cu")
		(at 140.375001 172.8025 90)
		(descr "Capacitor SMD 0402 (1005 Metric), square (rectangular) end terminal, IPC_7351 nominal, (Body size source: IPC-SM-782 page 76, https://www.pcb-3d.com/wordpress/wp-content/uploads/ipc-sm-782a_amendment_1_and_2.pdf)")
		(tags "capacitor 0402")
		(property "Reference" "C33"
			(at 0 1.17 270)
			(layer "B.SilkS")
			(hide yes)
			(effects
				(font
					(size 0.7 0.7)
					(thickness 0.15)
				)
				(justify left bottom mirror)
			)
		)
		(property "Value" "C_100n_0402"
			(at 0 -1.169 270)
			(layer "B.Fab")
			(effects
				(font
					(size 0.7 0.7)
					(thickness 0.15)
				)
				(justify left bottom mirror)
			)
		)
		(property "Datasheet" "https://www.murata.com/products/productdetail?partno=GRM155R61H104KE14%23"
			(at 0 0 90)
			(layer "F.Fab")
			(hide yes)
			(effects
				(font
					(size 1.27 1.27)
					(thickness 0.15)
				)
			)
		)
		(property "Author" "Antmicro"
			(at 313.177501 32.427499 0)
			(layer "B.Fab")
			(hide yes)
			(effects
				(font
					(size 1 1)
					(thickness 0.15)
				)
				(justify mirror)
			)
		)
		(property "Dielectric" "X5R"
			(at 313.177501 32.427499 0)
			(layer "B.Fab")
			(hide yes)
			(effects
				(font
					(size 1 1)
					(thickness 0.15)
				)
				(justify mirror)
			)
		)
		(property "License" "Apache-2.0"
			(at 313.177501 32.427499 0)
			(layer "B.Fab")
			(hide yes)
			(effects
				(font
					(size 1 1)
					(thickness 0.15)
				)
				(justify mirror)
			)
		)
		(property "MPN" "GRM155R61H104KE14D"
			(at 313.177501 32.427499 0)
			(layer "B.Fab")
			(hide yes)
			(effects
				(font
					(size 1 1)
					(thickness 0.15)
				)
				(justify mirror)
			)
		)
		(property "Manufacturer" "Murata"
			(at 313.177501 32.427499 0)
			(layer "B.Fab")
			(hide yes)
			(effects
				(font
					(size 1 1)
					(thickness 0.15)
				)
				(justify mirror)
			)
		)
		(property "Val" "100n"
			(at 313.177501 32.427499 0)
			(layer "B.Fab")
			(hide yes)
			(effects
				(font
					(size 1 1)
					(thickness 0.15)
				)
				(justify mirror)
			)
		)
		(property "Voltage" "50V"
			(at 313.177501 32.427499 0)
			(layer "B.Fab")
			(hide yes)
			(effects
				(font
					(size 1 1)
					(thickness 0.15)
				)
				(justify mirror)
			)
		)
		(sheetname "/FPGA power/")
		(sheetfile "fpga-power.kicad_sch")
		(attr smd)
		(fp_rect
			(start -0.9656 0.4572)
			(end 0.9652 -0.4828)
			(stroke
				(width 0.05)
				(type solid)
			)
			(fill no)
			(layer "B.CrtYd")
		)
		(fp_line
			(start 0.498 -0.248)
			(end -0.5 -0.248)
			(stroke
				(width 0.15)
				(type solid)
			)
			(layer "B.Fab")
		)
		(fp_line
			(start -0.5 -0.248)
			(end -0.5 0.25)
			(stroke
				(width 0.15)
				(type solid)
			)
			(layer "B.Fab")
		)
		(fp_line
			(start 0.498 0.25)
			(end 0.498 -0.248)
			(stroke
				(width 0.15)
				(type solid)
			)
			(layer "B.Fab")
		)
		(fp_line
			(start -0.5 0.25)
			(end 0.498 0.25)
			(stroke
				(width 0.15)
				(type solid)
			)
			(layer "B.Fab")
		)
		(pad "1" smd roundrect
			(at -0.5 0)
			(size 0.6 0.6)
			(layers "B.Cu" "B.Mask" "B.Paste")
			(roundrect_rratio 0.25)
			(net 1 "GND")
			(pintype "passive")
		)
		(pad "2" smd roundrect
			(at 0.498 0 90)
			(size 0.6 0.6)
			(layers "B.Cu" "B.Mask" "B.Paste")
			(roundrect_rratio 0.25)
			(net 227 "+1V0")
			(pintype "passive")
		)
	)
	(footprint "antmicro-footprints:TP_SMD_1mm"
		(layer "B.Cu")
		(at 199.2 141.2 180)
		(property "Reference" "TP26"
			(at 0 0.731898 0)
			(layer "B.SilkS")
			(hide yes)
			(effects
				(font
					(size 0.7 0.7)
					(thickness 0.15)
				)
				(justify left bottom mirror)
			)
		)
		(property "Value" "TP_1mm_SMD"
			(at 0 -1.4 0)
			(layer "B.Fab")
			(effects
				(font
					(size 0.7 0.7)
					(thickness 0.15)
				)
				(justify left bottom mirror)
			)
		)
		(property "MPN" ""
			(at 0 0 0)
			(unlocked yes)
			(layer "B.Fab")
			(hide yes)
			(effects
				(font
					(size 1 1)
					(thickness 0.15)
				)
				(justify mirror)
			)
		)
		(property "Manufacturer" ""
			(at 0 0 0)
			(unlocked yes)
			(layer "B.Fab")
			(hide yes)
			(effects
				(font
					(size 1 1)
					(thickness 0.15)
				)
				(justify mirror)
			)
		)
		(property "Author" "Antmicro"
			(at 0 0 0)
			(unlocked yes)
			(layer "B.Fab")
			(hide yes)
			(effects
				(font
					(size 1 1)
					(thickness 0.15)
				)
				(justify mirror)
			)
		)
		(property "License" "Apache-2.0"
			(at 0 0 0)
			(unlocked yes)
			(layer "B.Fab")
			(hide yes)
			(effects
				(font
					(size 1 1)
					(thickness 0.15)
				)
				(justify mirror)
			)
		)
		(sheetname "/Supply/")
		(sheetfile "supply.kicad_sch")
		(attr exclude_from_pos_files)
		(fp_circle
			(center 0 0)
			(end 0.6 0)
			(stroke
				(width 0.05)
				(type default)
			)
			(fill no)
			(layer "B.CrtYd")
		)
		(fp_text user "Author: Antmicro"
			(at -0.5 -4 0)
			(layer "B.Fab")
			(effects
				(font
					(size 0.7 0.7)
					(thickness 0.15)
				)
				(justify left bottom mirror)
			)
		)
		(fp_text user "License: Apache-2.0"
			(at -0.5 -5.2 0)
			(layer "B.Fab")
			(effects
				(font
					(size 0.7 0.7)
					(thickness 0.15)
				)
				(justify left bottom mirror)
			)
		)
		(fp_text user "${REFERENCE}"
			(at -0.5 -2.8 0)
			(layer "B.Fab")
			(effects
				(font
					(size 0.7 0.7)
					(thickness 0.15)
				)
				(justify left bottom mirror)
			)
		)
		(pad "1" smd circle
			(at 0 0 180)
			(size 1 1)
			(layers "B.Cu" "B.Mask")
			(net 41 "+3V3_AON")
			(pinfunction "1")
			(pintype "passive")
		)
	)
	(footprint "antmicro-footprints:C_0402_1005Metric"
		(layer "B.Cu")
		(at 104.95 171.988 90)
		(descr "Capacitor SMD 0402")
		(tags "capacitor SMD 0402")
		(property "Reference" "C237"
			(at 0 0.699 90)
			(layer "B.SilkS")
			(hide yes)
			(effects
				(font
					(size 0.7 0.7)
					(thickness 0.15)
				)
				(justify right bottom mirror)
			)
		)
		(property "Value" "C_100n_0402"
			(at -1.022927 -2.155213 90)
			(layer "B.Fab")
			(effects
				(font
					(size 0.7 0.7)
					(thickness 0.15)
				)
				(justify right bottom mirror)
			)
		)
		(property "Datasheet" "https://www.murata.com/products/productdetail?partno=GRM155R61H104KE14%23"
			(at 0 0 90)
			(layer "F.Fab")
			(hide yes)
			(effects
				(font
					(size 1.27 1.27)
					(thickness 0.15)
				)
			)
		)
		(property "Author" "Antmicro"
			(at 276.938 67.038 0)
			(layer "B.Fab")
			(hide yes)
			(effects
				(font
					(size 1 1)
					(thickness 0.15)
				)
				(justify mirror)
			)
		)
		(property "Dielectric" "X5R"
			(at 276.938 67.038 0)
			(layer "B.Fab")
			(hide yes)
			(effects
				(font
					(size 1 1)
					(thickness 0.15)
				)
				(justify mirror)
			)
		)
		(property "License" "Apache-2.0"
			(at 276.938 67.038 0)
			(layer "B.Fab")
			(hide yes)
			(effects
				(font
					(size 1 1)
					(thickness 0.15)
				)
				(justify mirror)
			)
		)
		(property "MPN" "GRM155R61H104KE14D"
			(at 276.938 67.038 0)
			(layer "B.Fab")
			(hide yes)
			(effects
				(font
					(size 1 1)
					(thickness 0.15)
				)
				(justify mirror)
			)
		)
		(property "Manufacturer" "Murata"
			(at 276.938 67.038 0)
			(layer "B.Fab")
			(hide yes)
			(effects
				(font
					(size 1 1)
					(thickness 0.15)
				)
				(justify mirror)
			)
		)
		(property "Val" "100n"
			(at 276.938 67.038 0)
			(layer "B.Fab")
			(hide yes)
			(effects
				(font
					(size 1 1)
					(thickness 0.15)
				)
				(justify mirror)
			)
		)
		(property "Voltage" "50V"
			(at 276.938 67.038 0)
			(layer "B.Fab")
			(hide yes)
			(effects
				(font
					(size 1 1)
					(thickness 0.15)
				)
				(justify mirror)
			)
		)
		(sheetname "/Debug FTDI/")
		(sheetfile "debug-ftdi.kicad_sch")
		(attr smd)
		(fp_rect
			(start -0.925 0.47)
			(end 0.925 -0.47)
			(stroke
				(width 0.05)
				(type default)
			)
			(fill no)
			(layer "B.CrtYd")
		)
		(fp_line
			(start 0.504 -0.248)
			(end -0.494 -0.248)
			(stroke
				(width 0.15)
				(type solid)
			)
			(layer "B.Fab")
		)
		(fp_line
			(start -0.494 -0.248)
			(end -0.494 0.25)
			(stroke
				(width 0.15)
				(type solid)
			)
			(layer "B.Fab")
		)
		(fp_line
			(start 0.504 0.25)
			(end 0.504 -0.248)
			(stroke
				(width 0.15)
				(type solid)
			)
			(layer "B.Fab")
		)
		(fp_line
			(start -0.494 0.25)
			(end 0.504 0.25)
			(stroke
				(width 0.15)
				(type solid)
			)
			(layer "B.Fab")
		)
		(pad "1" smd roundrect
			(at -0.48 0 90)
			(size 0.59 0.64)
			(layers "B.Cu" "B.Mask" "B.Paste")
			(roundrect_rratio 0.25)
			(net 1 "GND")
			(pintype "passive")
		)
		(pad "2" smd roundrect
			(at 0.48 0 90)
			(size 0.59 0.64)
			(layers "B.Cu" "B.Mask" "B.Paste")
			(roundrect_rratio 0.25)
			(net 6 "/Debug FTDI/FTDI_3V3")
			(pintype "passive")
		)
	)
)
